(kicad_pcb
	(version 20241229)
	(generator "pcbnew")
	(generator_version "9.0")
	(general
		(thickness 1.711)
		(legacy_teardrops no)
	)
	(paper "A4")
	(title_block
		(title "Antmicro Baseboard for Jetson AGX Thor")
		(date "2026-02-18")
		(rev "1.1.0")
		(company "Antmicro Ltd")
		(comment 1 "www.antmicro.com")
		(comment 9 "footprints 1-5 of 1170")
	)
	(layers
		(0 "F.Cu" signal)
		(4 "In1.Cu" signal)
		(6 "In2.Cu" signal)
		(8 "In3.Cu" signal)
		(10 "In4.Cu" jumper)
		(12 "In5.Cu" signal)
		(14 "In6.Cu" signal)
		(16 "In7.Cu" signal)
		(18 "In8.Cu" signal)
		(2 "B.Cu" signal)
		(9 "F.Adhes" user "F.Adhesive")
		(11 "B.Adhes" user "B.Adhesive")
		(13 "F.Paste" user)
		(15 "B.Paste" user)
		(5 "F.SilkS" user "F.Silkscreen")
		(7 "B.SilkS" user "B.Silkscreen")
		(1 "F.Mask" user)
		(3 "B.Mask" user)
		(17 "Dwgs.User" user "User.Drawings")
		(19 "Cmts.User" user "User.Comments")
		(21 "Eco1.User" user "User.Eco1")
		(23 "Eco2.User" user "User.Eco2")
		(25 "Edge.Cuts" user)
		(27 "Margin" user)
		(31 "F.CrtYd" user "F.Courtyard")
		(29 "B.CrtYd" user "B.Courtyard")
		(35 "F.Fab" user)
		(33 "B.Fab" user)
	)
	(footprint "antmicro-footprints:C_0805_2012Metric"
		(layer "F.Cu")
		(at 171.35 69.11 90)
		(descr "Capacitor SMD 0805")
		(tags "capacitor SMD 0805")
		(property "Reference" "C276"
			(at -1.43 -2.720532 90)
			(layer "F.SilkS")
			(effects
				(font
					(size 0.7 0.7)
					(thickness 0.15)
				)
				(justify left bottom)
			)
		)
		(property "Value" "C_22u_25V_0805"
			(at -2.055717 1.963152 90)
			(layer "F.Fab")
			(effects
				(font
					(size 0.7 0.7)
					(thickness 0.15)
				)
				(justify left bottom)
			)
		)
		(property "Datasheet" "https://product.samsungsem.com/mlcc/CL21A226MAYNNN.do"
			(at 0 0 90)
			(layer "F.Fab")
			(hide yes)
			(effects
				(font
					(size 1.27 1.27)
					(thickness 0.15)
				)
			)
		)
		(property "Description" "SMT Multilayer Ceramic Capacitor, 22uF, +/-20%, 25V, X5R, 0805 [2012 Metric]"
			(at 0 0 90)
			(layer "F.Fab")
			(hide yes)
			(effects
				(font
					(size 1.27 1.27)
					(thickness 0.15)
				)
			)
		)
		(property "MPN" "CL21A226MAYNNNE"
			(at 0 0 90)
			(unlocked yes)
			(layer "F.Fab")
			(hide yes)
			(effects
				(font
					(size 1 1)
					(thickness 0.15)
				)
			)
		)
		(property "Manufacturer" "Samsung Electro-Mechanics"
			(at 0 0 90)
			(unlocked yes)
			(layer "F.Fab")
			(hide yes)
			(effects
				(font
					(size 1 1)
					(thickness 0.15)
				)
			)
		)
		(property "License" "Apache-2.0"
			(at 0 0 90)
			(unlocked yes)
			(layer "F.Fab")
			(hide yes)
			(effects
				(font
					(size 1 1)
					(thickness 0.15)
				)
			)
		)
		(property "Author" "Antmicro"
			(at 0 0 90)
			(unlocked yes)
			(layer "F.Fab")
			(hide yes)
			(effects
				(font
					(size 1 1)
					(thickness 0.15)
				)
			)
		)
		(property "Val" "22u"
			(at 0 0 90)
			(unlocked yes)
			(layer "F.Fab")
			(hide yes)
			(effects
				(font
					(size 1 1)
					(thickness 0.15)
				)
			)
		)
		(property "Voltage" "25V"
			(at 0 0 90)
			(unlocked yes)
			(layer "F.Fab")
			(hide yes)
			(effects
				(font
					(size 1 1)
					(thickness 0.15)
				)
			)
		)
		(property "Dielectric" "X5R"
			(at 0 0 90)
			(unlocked yes)
			(layer "F.Fab")
			(hide yes)
			(effects
				(font
					(size 1 1)
					(thickness 0.15)
				)
			)
		)
		(property "Public" "False"
			(at 0 0 90)
			(unlocked yes)
			(layer "F.Fab")
			(hide yes)
			(effects
				(font
					(size 1 1)
					(thickness 0.15)
				)
			)
		)
		(component_classes
			(class "DCDC_20V")
		)
		(sheetname "/DCDC/")
		(sheetfile "dcdc.kicad_sch")
		(attr smd)
		(fp_line
			(start -0.3 -0.7)
			(end 0.3 -0.7)
			(stroke
				(width 0.15)
				(type solid)
			)
			(layer "F.SilkS")
		)
		(fp_line
			(start -0.3 0.7)
			(end 0.3 0.7)
			(stroke
				(width 0.15)
				(type solid)
			)
			(layer "F.SilkS")
		)
		(fp_rect
			(start 1.95 -0.9)
			(end -1.95 0.9)
			(stroke
				(width 0.05)
				(type default)
			)
			(fill no)
			(layer "F.CrtYd")
		)
		(fp_rect
			(start -0.95 -0.675)
			(end 0.95 0.675)
			(stroke
				(width 0.15)
				(type solid)
			)
			(fill no)
			(layer "F.Fab")
		)
		(fp_text user "${REFERENCE}"
			(at -1.9 3.947 90)
			(layer "F.Fab")
			(effects
				(font
					(size 0.7 0.7)
					(thickness 0.15)
				)
				(justify left bottom)
			)
		)
		(fp_text user "License: Apache-2.0"
			(at -1.9 4.947 90)
			(layer "F.Fab")
			(effects
				(font
					(size 0.7 0.7)
					(thickness 0.15)
				)
				(justify left bottom)
			)
		)
		(fp_text user "Author: Antmicro"
			(at -1.9 5.947 90)
			(layer "F.Fab")
			(effects
				(font
					(size 0.7 0.7)
					(thickness 0.15)
				)
				(justify left bottom)
			)
		)
		(pad "1" smd roundrect
			(at -1.1 0 90)
			(size 1.2 1.3)
			(layers "F.Cu" "F.Mask" "F.Paste")
			(roundrect_rratio 0.25)
			(net 1 "GND")
			(pintype "passive")
		)
		(pad "2" smd roundrect
			(at 1.1 0 90)
			(size 1.2 1.3)
			(layers "F.Cu" "F.Mask" "F.Paste")
			(roundrect_rratio 0.25)
			(net 13 "VCC")
			(pintype "passive")
		)
	)
	(footprint "antmicro-footprints:C_0805_2012Metric"
		(layer "F.Cu")
		(at 126.17 57.54)
		(descr "Capacitor SMD 0805")
		(tags "capacitor SMD 0805")
		(property "Reference" "C373"
			(at -8.76 8.85 0)
			(layer "F.SilkS")
			(effects
				(font
					(size 0.7 0.7)
					(thickness 0.15)
				)
				(justify left bottom)
			)
		)
		(property "Value" "C_22u_25V_0805"
			(at -2.055717 1.963153 0)
			(layer "F.Fab")
			(effects
				(font
					(size 0.7 0.7)
					(thickness 0.15)
				)
				(justify left bottom)
			)
		)
		(property "Datasheet" "https://product.samsungsem.com/mlcc/CL21A226MAYNNN.do"
			(at 0 0 0)
			(layer "F.Fab")
			(hide yes)
			(effects
				(font
					(size 1.27 1.27)
					(thickness 0.15)
				)
			)
		)
		(property "Description" "SMT Multilayer Ceramic Capacitor, 22uF, +/-20%, 25V, X5R, 0805 [2012 Metric]"
			(at 0 0 0)
			(layer "F.Fab")
			(hide yes)
			(effects
				(font
					(size 1.27 1.27)
					(thickness 0.15)
				)
			)
		)
		(property "MPN" "CL21A226MAYNNNE"
			(at 0 0 0)
			(unlocked yes)
			(layer "F.Fab")
			(hide yes)
			(effects
				(font
					(size 1 1)
					(thickness 0.15)
				)
			)
		)
		(property "Manufacturer" "Samsung Electro-Mechanics"
			(at 0 0 0)
			(unlocked yes)
			(layer "F.Fab")
			(hide yes)
			(effects
				(font
					(size 1 1)
					(thickness 0.15)
				)
			)
		)
		(property "License" "Apache-2.0"
			(at 0 0 0)
			(unlocked yes)
			(layer "F.Fab")
			(hide yes)
			(effects
				(font
					(size 1 1)
					(thickness 0.15)
				)
			)
		)
		(property "Author" "Antmicro"
			(at 0 0 0)
			(unlocked yes)
			(layer "F.Fab")
			(hide yes)
			(effects
				(font
					(size 1 1)
					(thickness 0.15)
				)
			)
		)
		(property "Val" "22u"
			(at 0 0 0)
			(unlocked yes)
			(layer "F.Fab")
			(hide yes)
			(effects
				(font
					(size 1 1)
					(thickness 0.15)
				)
			)
		)
		(property "Voltage" "25V"
			(at 0 0 0)
			(unlocked yes)
			(layer "F.Fab")
			(hide yes)
			(effects
				(font
					(size 1 1)
					(thickness 0.15)
				)
			)
		)
		(property "Dielectric" "X5R"
			(at 0 0 0)
			(unlocked yes)
			(layer "F.Fab")
			(hide yes)
			(effects
				(font
					(size 1 1)
					(thickness 0.15)
				)
			)
		)
		(property "Public" "False"
			(at 0 0 0)
			(unlocked yes)
			(layer "F.Fab")
			(hide yes)
			(effects
				(font
					(size 1 1)
					(thickness 0.15)
				)
			)
		)
		(sheetname "/DCDC/")
		(sheetfile "dcdc.kicad_sch")
		(attr smd)
		(fp_line
			(start -0.3 -0.7)
			(end 0.3 -0.7)
			(stroke
				(width 0.15)
				(type solid)
			)
			(layer "F.SilkS")
		)
		(fp_line
			(start -0.3 0.7)
			(end 0.3 0.7)
			(stroke
				(width 0.15)
				(type solid)
			)
			(layer "F.SilkS")
		)
		(fp_poly
			(pts
				(xy 1.95 -0.9) (xy 1.95 0.9) (xy -1.95 0.9) (xy -1.95 -0.9)
			)
			(stroke
				(width 0.05)
				(type default)
			)
			(fill no)
			(layer "F.CrtYd")
		)
		(fp_poly
			(pts
				(xy -0.95 -0.675001) (xy -0.95 0.675001) (xy 0.95 0.675001) (xy 0.95 -0.675001)
			)
			(stroke
				(width 0.15)
				(type solid)
			)
			(fill no)
			(layer "F.Fab")
		)
		(fp_text user "${REFERENCE}"
			(at -1.899999 3.947 0)
			(layer "F.Fab")
			(effects
				(font
					(size 0.7 0.7)
					(thickness 0.15)
				)
				(justify left bottom)
			)
		)
		(fp_text user "Author: Antmicro"
			(at -1.9 5.947 0)
			(layer "F.Fab")
			(effects
				(font
					(size 0.7 0.7)
					(thickness 0.15)
				)
				(justify left bottom)
			)
		)
		(fp_text user "License: Apache-2.0"
			(at -1.9 4.947 0)
			(layer "F.Fab")
			(effects
				(font
					(size 0.7 0.7)
					(thickness 0.15)
				)
				(justify left bottom)
			)
		)
		(pad "1" smd roundrect
			(at -1.099999 0)
			(size 1.2 1.3)
			(layers "F.Cu" "F.Mask" "F.Paste")
			(roundrect_rratio 0.25)
			(net 1 "GND")
			(pintype "passive")
		)
		(pad "2" smd roundrect
			(at 1.099999 0)
			(size 1.2 1.3)
			(layers "F.Cu" "F.Mask" "F.Paste")
			(roundrect_rratio 0.25)
			(net 13 "VCC")
			(pintype "passive")
		)
	)
	(footprint "antmicro-footprints:R_0402_1005Metric"
		(layer "F.Cu")
		(at 94 58.5)
		(descr "Resistor SMD 0402")
		(tags "resistor SMD 0402")
		(property "Reference" "R288"
			(at 6.9 1.68 0)
			(layer "F.SilkS")
			(effects
				(font
					(size 0.7 0.7)
					(thickness 0.15)
				)
				(justify left bottom)
			)
		)
		(property "Value" "R_47k_0402"
			(at -1.011843 1.772046 0)
			(layer "F.Fab")
			(effects
				(font
					(size 0.7 0.7)
					(thickness 0.15)
				)
				(justify left bottom)
			)
		)
		(property "Datasheet" "https://www.bourns.com/docs/product-datasheets/cr.pdf"
			(at 0 0 0)
			(layer "F.Fab")
			(hide yes)
			(effects
				(font
					(size 1.27 1.27)
					(thickness 0.15)
				)
			)
		)
		(property "Description" "SMD Chip Resistor, 47 kohm, ± 1%, 62.5 mW, 0402 [1005 Metric], Thick Film, General Purpose"
			(at 0 0 0)
			(layer "F.Fab")
			(hide yes)
			(effects
				(font
					(size 1.27 1.27)
					(thickness 0.15)
				)
			)
		)
		(property "MPN" "CR0402-FX-4702GLF"
			(at 0 0 0)
			(unlocked yes)
			(layer "F.Fab")
			(hide yes)
			(effects
				(font
					(size 1 1)
					(thickness 0.15)
				)
			)
		)
		(property "Manufacturer" "Bourns"
			(at 0 0 0)
			(unlocked yes)
			(layer "F.Fab")
			(hide yes)
			(effects
				(font
					(size 1 1)
					(thickness 0.15)
				)
			)
		)
		(property "License" "Apache-2.0"
			(at 0 0 0)
			(unlocked yes)
			(layer "F.Fab")
			(hide yes)
			(effects
				(font
					(size 1 1)
					(thickness 0.15)
				)
			)
		)
		(property "Author" "Antmicro"
			(at 0 0 0)
			(unlocked yes)
			(layer "F.Fab")
			(hide yes)
			(effects
				(font
					(size 1 1)
					(thickness 0.15)
				)
			)
		)
		(property "Val" "47k"
			(at 0 0 0)
			(unlocked yes)
			(layer "F.Fab")
			(hide yes)
			(effects
				(font
					(size 1 1)
					(thickness 0.15)
				)
			)
		)
		(property "Tolerance" "1%"
			(at 0 0 0)
			(unlocked yes)
			(layer "F.Fab")
			(hide yes)
			(effects
				(font
					(size 1 1)
					(thickness 0.15)
				)
			)
		)
		(sheetname "/SoM_Power/")
		(sheetfile "som_power.kicad_sch")
		(attr smd)
		(fp_poly
			(pts
				(xy -0.925 -0.47) (xy -0.925 0.47) (xy 0.925 0.47) (xy 0.925 -0.47)
			)
			(stroke
				(width 0.05)
				(type default)
			)
			(fill no)
			(layer "F.CrtYd")
		)
		(fp_poly
			(pts
				(xy -0.5 -0.25) (xy -0.5 0.25) (xy 0.5 0.25) (xy 0.5 -0.25)
			)
			(stroke
				(width 0.15)
				(type solid)
			)
			(fill no)
			(layer "F.Fab")
		)
		(fp_text user "Author: Antmicro"
			(at -0.95 4.169 0)
			(layer "F.Fab")
			(effects
				(font
					(size 0.7 0.7)
					(thickness 0.15)
				)
				(justify left bottom)
			)
		)
		(fp_text user "License: Apache-2.0"
			(at -0.949999 5.169 0)
			(layer "F.Fab")
			(effects
				(font
					(size 0.7 0.7)
					(thickness 0.15)
				)
				(justify left bottom)
			)
		)
		(fp_text user "${REFERENCE}"
			(at -0.95 3.168 0)
			(layer "F.Fab")
			(effects
				(font
					(size 0.7 0.7)
					(thickness 0.15)
				)
				(justify left bottom)
			)
		)
		(pad "1" smd roundrect
			(at -0.48 0)
			(size 0.59 0.64)
			(layers "F.Cu" "F.Mask" "F.Paste")
			(roundrect_rratio 0.25)
			(net 610 "/SoM_Power/~{PWR_BTN}")
			(pintype "passive")
		)
		(pad "2" smd roundrect
			(at 0.48 0)
			(size 0.59 0.64)
			(layers "F.Cu" "F.Mask" "F.Paste")
			(roundrect_rratio 0.25)
			(net 491 "+5V_AON")
			(pintype "passive")
		)
	)
	(footprint "antmicro-footprints:C_0805_2012Metric"
		(layer "F.Cu")
		(at 165.88 73.31 -90)
		(descr "Capacitor SMD 0805")
		(tags "capacitor SMD 0805")
		(property "Reference" "C295"
			(at 1.78449 -1.468678 90)
			(layer "F.SilkS")
			(effects
				(font
					(size 0.7 0.7)
					(thickness 0.15)
				)
				(justify right top)
			)
		)
		(property "Value" "C_22u_25V_0805"
			(at -2.055717 1.963152 90)
			(layer "F.Fab")
			(effects
				(font
					(size 0.7 0.7)
					(thickness 0.15)
				)
				(justify right top)
			)
		)
		(property "Datasheet" "https://product.samsungsem.com/mlcc/CL21A226MAYNNN.do"
			(at 0 0 90)
			(layer "F.Fab")
			(hide yes)
			(effects
				(font
					(size 1.27 1.27)
					(thickness 0.15)
				)
			)
		)
		(property "Description" "SMT Multilayer Ceramic Capacitor, 22uF, +/-20%, 25V, X5R, 0805 [2012 Metric]"
			(at 0 0 90)
			(layer "F.Fab")
			(hide yes)
			(effects
				(font
					(size 1.27 1.27)
					(thickness 0.15)
				)
			)
		)
		(property "MPN" "CL21A226MAYNNNE"
			(at 0 0 270)
			(unlocked yes)
			(layer "F.Fab")
			(hide yes)
			(effects
				(font
					(size 1 1)
					(thickness 0.15)
				)
			)
		)
		(property "Manufacturer" "Samsung Electro-Mechanics"
			(at 0 0 270)
			(unlocked yes)
			(layer "F.Fab")
			(hide yes)
			(effects
				(font
					(size 1 1)
					(thickness 0.15)
				)
			)
		)
		(property "License" "Apache-2.0"
			(at 0 0 270)
			(unlocked yes)
			(layer "F.Fab")
			(hide yes)
			(effects
				(font
					(size 1 1)
					(thickness 0.15)
				)
			)
		)
		(property "Author" "Antmicro"
			(at 0 0 270)
			(unlocked yes)
			(layer "F.Fab")
			(hide yes)
			(effects
				(font
					(size 1 1)
					(thickness 0.15)
				)
			)
		)
		(property "Val" "22u"
			(at 0 0 270)
			(unlocked yes)
			(layer "F.Fab")
			(hide yes)
			(effects
				(font
					(size 1 1)
					(thickness 0.15)
				)
			)
		)
		(property "Voltage" "25V"
			(at 0 0 270)
			(unlocked yes)
			(layer "F.Fab")
			(hide yes)
			(effects
				(font
					(size 1 1)
					(thickness 0.15)
				)
			)
		)
		(property "Dielectric" "X5R"
			(at 0 0 270)
			(unlocked yes)
			(layer "F.Fab")
			(hide yes)
			(effects
				(font
					(size 1 1)
					(thickness 0.15)
				)
			)
		)
		(property "Public" "False"
			(at 0 0 270)
			(unlocked yes)
			(layer "F.Fab")
			(hide yes)
			(effects
				(font
					(size 1 1)
					(thickness 0.15)
				)
			)
		)
		(component_classes
			(class "DCDC_20V")
		)
		(sheetname "/DCDC/")
		(sheetfile "dcdc.kicad_sch")
		(attr smd)
		(fp_line
			(start -0.3 0.7)
			(end 0.3 0.7)
			(stroke
				(width 0.15)
				(type solid)
			)
			(layer "F.SilkS")
		)
		(fp_line
			(start -0.3 -0.7)
			(end 0.3 -0.7)
			(stroke
				(width 0.15)
				(type solid)
			)
			(layer "F.SilkS")
		)
		(fp_rect
			(start 1.95 -0.9)
			(end -1.95 0.9)
			(stroke
				(width 0.05)
				(type default)
			)
			(fill no)
			(layer "F.CrtYd")
		)
		(fp_rect
			(start -0.95 -0.675)
			(end 0.95 0.675)
			(stroke
				(width 0.15)
				(type solid)
			)
			(fill no)
			(layer "F.Fab")
		)
		(fp_text user "Author: Antmicro"
			(at -1.9 5.947 90)
			(layer "F.Fab")
			(effects
				(font
					(size 0.7 0.7)
					(thickness 0.15)
				)
				(justify right top)
			)
		)
		(fp_text user "${REFERENCE}"
			(at -1.9 3.947 90)
			(layer "F.Fab")
			(effects
				(font
					(size 0.7 0.7)
					(thickness 0.15)
				)
				(justify right top)
			)
		)
		(fp_text user "License: Apache-2.0"
			(at -1.9 4.947 90)
			(layer "F.Fab")
			(effects
				(font
					(size 0.7 0.7)
					(thickness 0.15)
				)
				(justify right top)
			)
		)
		(pad "1" smd roundrect
			(at -1.1 0 270)
			(size 1.2 1.3)
			(layers "F.Cu" "F.Mask" "F.Paste")
			(roundrect_rratio 0.25)
			(net 1 "GND")
			(pintype "passive")
		)
		(pad "2" smd roundrect
			(at 1.1 0 270)
			(size 1.2 1.3)
			(layers "F.Cu" "F.Mask" "F.Paste")
			(roundrect_rratio 0.25)
			(net 1105 "/DCDC/20V_OUT")
			(pintype "passive")
		)
	)
	(footprint "antmicro-footprints:R_0402_1005Metric"
		(layer "F.Cu")
		(at 91.5 149.63 90)
		(descr "Resistor SMD 0402")
		(tags "resistor SMD 0402")
		(property "Reference" "R193"
			(at -3.77 0.5 90)
			(layer "F.SilkS")
			(effects
				(font
					(size 0.7 0.7)
					(thickness 0.15)
				)
				(justify left bottom)
			)
		)
		(property "Value" "R_49R9_0402"
			(at -1.011843 1.772046 90)
			(layer "F.Fab")
			(effects
				(font
					(size 0.7 0.7)
					(thickness 0.15)
				)
				(justify left bottom)
			)
		)
		(property "Datasheet" "https://www.bourns.com/docs/product-datasheets/cr.pdf"
			(at 0 0 90)
			(layer "F.Fab")
			(hide yes)
			(effects
				(font
					(size 1.27 1.27)
					(thickness 0.15)
				)
			)
		)
		(property "Description" "SMD Chip Resistor, 49.9 ohm, ± 1%, 62.5 mW, 0402 [1005 Metric], Thick Film, General Purpose"
			(at 0 0 90)
			(layer "F.Fab")
			(hide yes)
			(effects
				(font
					(size 1.27 1.27)
					(thickness 0.15)
				)
			)
		)
		(property "MPN" "CR0402-FX-49R9GLF"
			(at 0 0 90)
			(unlocked yes)
			(layer "F.Fab")
			(hide yes)
			(effects
				(font
					(size 1 1)
					(thickness 0.15)
				)
			)
		)
		(property "Manufacturer" "Bourns"
			(at 0 0 90)
			(unlocked yes)
			(layer "F.Fab")
			(hide yes)
			(effects
				(font
					(size 1 1)
					(thickness 0.15)
				)
			)
		)
		(property "License" "Apache-2.0"
			(at 0 0 90)
			(unlocked yes)
			(layer "F.Fab")
			(hide yes)
			(effects
				(font
					(size 1 1)
					(thickness 0.15)
				)
			)
		)
		(property "Author" "Antmicro"
			(at 0 0 90)
			(unlocked yes)
			(layer "F.Fab")
			(hide yes)
			(effects
				(font
					(size 1 1)
					(thickness 0.15)
				)
			)
		)
		(property "Val" "49R9"
			(at 0 0 90)
			(unlocked yes)
			(layer "F.Fab")
			(hide yes)
			(effects
				(font
					(size 1 1)
					(thickness 0.15)
				)
			)
		)
		(property "Tolerance" "1%"
			(at 0 0 90)
			(unlocked yes)
			(layer "F.Fab")
			(hide yes)
			(effects
				(font
					(size 1 1)
					(thickness 0.15)
				)
			)
		)
		(sheetname "/SoM_IO2/")
		(sheetfile "som_io2.kicad_sch")
		(attr smd)
		(fp_poly
			(pts
				(xy -0.925 -0.47) (xy 0.925 -0.47) (xy 0.925 0.47) (xy -0.925 0.47)
			)
			(stroke
				(width 0.05)
				(type default)
			)
			(fill no)
			(layer "F.CrtYd")
		)
		(fp_poly
			(pts
				(xy -0.5 -0.25) (xy 0.5 -0.25) (xy 0.5 0.25) (xy -0.5 0.25)
			)
			(stroke
				(width 0.15)
				(type solid)
			)
			(fill no)
			(layer "F.Fab")
		)
		(fp_text user "License: Apache-2.0"
			(at -0.949999 5.169 90)
			(layer "F.Fab")
			(effects
				(font
					(size 0.7 0.7)
					(thickness 0.15)
				)
				(justify left bottom)
			)
		)
		(fp_text user "Author: Antmicro"
			(at -0.95 4.169 90)
			(layer "F.Fab")
			(effects
				(font
					(size 0.7 0.7)
					(thickness 0.15)
				)
				(justify left bottom)
			)
		)
		(fp_text user "${REFERENCE}"
			(at -0.95 3.168 90)
			(layer "F.Fab")
			(effects
				(font
					(size 0.7 0.7)
					(thickness 0.15)
				)
				(justify left bottom)
			)
		)
		(pad "1" smd roundrect
			(at -0.48 0 90)
			(size 0.59 0.64)
			(layers "F.Cu" "F.Mask" "F.Paste")
			(roundrect_rratio 0.25)
			(net 1 "GND")
			(pintype "passive")
		)
		(pad "2" smd roundrect
			(at 0.48 0 90)
			(size 0.59 0.64)
			(layers "F.Cu" "F.Mask" "F.Paste")
			(roundrect_rratio 0.25)
			(net 898 "/SoM_IO2/C2_REFCLK+")
			(pintype "passive")
		)
	)
)
